(kicad_pcb
	(version 20260206)
	(generator "pcbnew")
	(generator_version "10.0")
	(general
		(thickness 1.6)
		(legacy_teardrops no)
	)
	(paper "A4")
	(title_block
		(title "12092022_DA0F0TFB6D0_F0T_FAN_BOARD_MP5048_D_brd_v02_OCP.brd")
		(comment 1 "Grand Teton / footprints 241-243 of 924")
	)
	(layers
		(0 "F.Cu" signal "TOP")
		(4 "In1.Cu" signal "GND")
		(6 "In2.Cu" signal "IN1")
		(8 "In3.Cu" signal "IN2")
		(10 "In4.Cu" signal "GND1")
		(2 "B.Cu" signal "BOTTOM")
		(9 "F.Adhes" user "F.Adhesive")
		(11 "B.Adhes" user "B.Adhesive")
		(13 "F.Paste" user "Package Geometry/Pastemask Top")
		(15 "B.Paste" user "Package Geometry/Pastemask Bottom")
		(5 "F.SilkS" user "Ref Des/Silkscreen Top")
		(7 "B.SilkS" user "Ref Des/Silkscreen Bottom")
		(1 "F.Mask" user "Board Geometry/Soldermask Top")
		(3 "B.Mask" user "Board Geometry/Soldermask Bottom")
		(17 "Dwgs.User" user "User.Drawings")
		(19 "Cmts.User" user "User.Comments")
		(21 "Eco1.User" user "User.Eco1")
		(23 "Eco2.User" user "User.Eco2")
		(25 "Edge.Cuts" user "Board Geometry/Outline")
		(27 "Margin" user)
		(31 "F.CrtYd" user "Package Geometry/Place Bound Top")
		(29 "B.CrtYd" user "Package Geometry/Place Bound Bottom")
		(35 "F.Fab" user "Ref Des/Assembly Top")
		(33 "B.Fab" user "Ref Des/Assembly Bottom")
	)
	(footprint ""
		(layer "F.Cu")
		(at 20.955 -129.159 -90)
		(property "Reference" "U330"
			(at 3.93573 1.75514 0)
			(unlocked yes)
			(layer "F.SilkS")
			(effects
				(font
					(size 0.7874 0.5842)
					(thickness 0.1524)
				)
				(justify left)
			)
		)
		(property "Value" ""
			(at 0 0 270)
			(layer "F.Fab")
			(effects
				(font
					(size 1.27 1.27)
				)
			)
		)
		(duplicate_pad_numbers_are_jumpers no)
		(fp_line
			(start -0.4064 2.54)
			(end -0.4064 3.302)
			(stroke
				(width 0.1524)
				(type default)
			)
			(layer "F.SilkS")
		)
		(fp_line
			(start -2.050034 2.050034)
			(end -1.417828 2.050034)
			(stroke
				(width 0.1524)
				(type default)
			)
			(layer "F.SilkS")
		)
		(fp_line
			(start 1.42367 2.050034)
			(end 2.050034 2.050034)
			(stroke
				(width 0.1524)
				(type default)
			)
			(layer "F.SilkS")
		)
		(fp_line
			(start 2.050034 2.050034)
			(end 2.050034 1.41732)
			(stroke
				(width 0.1524)
				(type default)
			)
			(layer "F.SilkS")
		)
		(fp_line
			(start -2.050034 1.41986)
			(end -2.050034 2.050034)
			(stroke
				(width 0.1524)
				(type default)
			)
			(layer "F.SilkS")
		)
		(fp_line
			(start 3.048 1.2192)
			(end 2.54 1.2192)
			(stroke
				(width 0.1524)
				(type default)
			)
			(layer "F.SilkS")
		)
		(fp_line
			(start -2.54508 0.398272)
			(end -3.05308 0.398272)
			(stroke
				(width 0.1524)
				(type default)
			)
			(layer "F.SilkS")
		)
		(fp_line
			(start 3.302 -0.8128)
			(end 2.54 -0.8128)
			(stroke
				(width 0.1524)
				(type default)
			)
			(layer "F.SilkS")
		)
		(fp_line
			(start 2.050034 -1.415796)
			(end 2.050034 -2.050034)
			(stroke
				(width 0.1524)
				(type default)
			)
			(layer "F.SilkS")
		)
		(fp_line
			(start -2.050034 -2.050034)
			(end -2.050034 -1.4224)
			(stroke
				(width 0.1524)
				(type default)
			)
			(layer "F.SilkS")
		)
		(fp_line
			(start -1.42367 -2.050034)
			(end -2.050034 -2.050034)
			(stroke
				(width 0.1524)
				(type default)
			)
			(layer "F.SilkS")
		)
		(fp_line
			(start 2.050034 -2.050034)
			(end 1.41859 -2.050034)
			(stroke
				(width 0.1524)
				(type default)
			)
			(layer "F.SilkS")
		)
		(fp_line
			(start 0 -3.048)
			(end 0 -2.54)
			(stroke
				(width 0.1524)
				(type default)
			)
			(layer "F.SilkS")
		)
		(fp_poly
			(pts
				(xy -3.5052 -1.707896) (xy -3.5052 -0.691896) (xy -2.4892 -1.199896)
			)
			(stroke
				(width 0)
				(type default)
			)
			(fill yes)
			(layer "F.SilkS")
		)
		(fp_line
			(start -0.396748 2.568448)
			(end -0.396748 3.330448)
			(stroke
				(width 0.1)
				(type default)
			)
			(layer "F.Fab")
		)
		(fp_line
			(start -2.050034 2.050034)
			(end 2.050034 2.050034)
			(stroke
				(width 0.1)
				(type default)
			)
			(layer "F.Fab")
		)
		(fp_line
			(start 2.050034 2.050034)
			(end 2.050034 -2.050034)
			(stroke
				(width 0.1)
				(type default)
			)
			(layer "F.Fab")
		)
		(fp_line
			(start 3.062732 1.198372)
			(end 2.554732 1.198372)
			(stroke
				(width 0.1)
				(type default)
			)
			(layer "F.Fab")
		)
		(fp_line
			(start -2.54508 0.398272)
			(end -3.05308 0.398272)
			(stroke
				(width 0.1)
				(type default)
			)
			(layer "F.Fab")
		)
		(fp_line
			(start 3.319272 -0.80264)
			(end 2.557272 -0.80264)
			(stroke
				(width 0.1)
				(type default)
			)
			(layer "F.Fab")
		)
		(fp_line
			(start -2.050034 -2.050034)
			(end -2.050034 2.050034)
			(stroke
				(width 0.1)
				(type default)
			)
			(layer "F.Fab")
		)
		(fp_line
			(start 2.050034 -2.050034)
			(end -2.050034 -2.050034)
			(stroke
				(width 0.1)
				(type default)
			)
			(layer "F.Fab")
		)
		(fp_line
			(start 0.009652 -3.052572)
			(end 0.009652 -2.544572)
			(stroke
				(width 0.1)
				(type default)
			)
			(layer "F.Fab")
		)
		(fp_poly
			(pts
				(xy -3.5052 -1.707896) (xy -3.5052 -0.691896) (xy -2.4892 -1.199896)
			)
			(stroke
				(width 0)
				(type default)
			)
			(fill yes)
			(layer "F.Fab")
		)
		(fp_text user "14"
			(at 0.30734 3.18897 270)
			(unlocked yes)
			(layer "F.SilkS")
			(effects
				(font
					(size 0.635 0.4064)
					(thickness 0.1524)
				)
				(justify left)
			)
		)
		(fp_text user "8"
			(at -1.92405 2.586482 270)
			(unlocked yes)
			(layer "F.SilkS")
			(effects
				(font
					(size 0.635 0.4064)
					(thickness 0.1524)
				)
				(justify left)
			)
		)
		(fp_text user "15"
			(at 2.630932 2.33045 0)
			(unlocked yes)
			(layer "F.SilkS")
			(effects
				(font
					(size 0.635 0.4064)
					(thickness 0.1524)
				)
				(justify left)
			)
		)
		(fp_text user "7"
			(at -2.563368 1.8923 0)
			(unlocked yes)
			(layer "F.SilkS")
			(effects
				(font
					(size 0.635 0.4064)
					(thickness 0.1524)
				)
				(justify left)
			)
		)
		(fp_text user "21"
			(at 2.618232 -1.3843 0)
			(unlocked yes)
			(layer "F.SilkS")
			(effects
				(font
					(size 0.635 0.4064)
					(thickness 0.1524)
				)
				(justify left)
			)
		)
		(fp_text user "28"
			(at -2.38125 -2.576068 270)
			(unlocked yes)
			(layer "F.SilkS")
			(effects
				(font
					(size 0.635 0.4064)
					(thickness 0.1524)
				)
				(justify left)
			)
		)
		(fp_text user "22"
			(at 1.41605 -2.684018 270)
			(unlocked yes)
			(layer "F.SilkS")
			(effects
				(font
					(size 0.635 0.4064)
					(thickness 0.1524)
				)
				(justify left)
			)
		)
		(fp_text user "14"
			(at 1.3208 2.745232 270)
			(unlocked yes)
			(layer "F.Fab")
			(effects
				(font
					(size 0.635 0.4064)
					(thickness 0.1524)
				)
				(justify left)
			)
		)
		(fp_text user "8"
			(at -1.92405 2.586482 270)
			(unlocked yes)
			(layer "F.Fab")
			(effects
				(font
					(size 0.635 0.4064)
					(thickness 0.1524)
				)
				(justify left)
			)
		)
		(fp_text user "15"
			(at 2.630932 2.33045 0)
			(unlocked yes)
			(layer "F.Fab")
			(effects
				(font
					(size 0.635 0.4064)
					(thickness 0.1524)
				)
				(justify left)
			)
		)
		(fp_text user "7"
			(at -2.563368 1.8923 0)
			(unlocked yes)
			(layer "F.Fab")
			(effects
				(font
					(size 0.635 0.4064)
					(thickness 0.1524)
				)
				(justify left)
			)
		)
		(fp_text user "21"
			(at 2.618232 -1.3843 0)
			(unlocked yes)
			(layer "F.Fab")
			(effects
				(font
					(size 0.635 0.4064)
					(thickness 0.1524)
				)
				(justify left)
			)
		)
		(fp_text user "28"
			(at -2.38125 -2.576068 270)
			(unlocked yes)
			(layer "F.Fab")
			(effects
				(font
					(size 0.635 0.4064)
					(thickness 0.1524)
				)
				(justify left)
			)
		)
		(fp_text user "22"
			(at 1.41605 -2.684018 270)
			(unlocked yes)
			(layer "F.Fab")
			(effects
				(font
					(size 0.635 0.4064)
					(thickness 0.1524)
				)
				(justify left)
			)
		)
		(pad "1" smd rect
			(at -1.999996 -1.199896)
			(size 0.1778 0.8128)
			(layers "F.Cu" "F.Mask" "F.Paste")
			(net "MAX31790_U330_FREQ_START")
		)
		(pad "2" smd rect
			(at -1.999996 -0.8001)
			(size 0.1778 0.8128)
			(layers "F.Cu" "F.Mask" "F.Paste")
			(net "MAX31790_U330_SPIN_START")
		)
		(pad "3" smd rect
			(at -1.999996 -0.40005)
			(size 0.1778 0.8128)
			(layers "F.Cu" "F.Mask" "F.Paste")
			(net "MAX31790_U330_ADD1")
		)
		(pad "4" smd rect
			(at -1.999996 0)
			(size 0.1778 0.8128)
			(layers "F.Cu" "F.Mask" "F.Paste")
			(net "MAX31790_U330_ADD0")
		)
		(pad "5" smd rect
			(at -1.999996 0.40005)
			(size 0.1778 0.8128)
			(layers "F.Cu" "F.Mask" "F.Paste")
			(net "MAX31790_U330_WD_START")
		)
		(pad "6" smd rect
			(at -1.999996 0.8001)
			(size 0.1778 0.8128)
			(layers "F.Cu" "F.Mask" "F.Paste")
			(net "TP_U330_XTAL2")
		)
		(pad "7" smd rect
			(at -1.999996 1.199896)
			(size 0.1778 0.8128)
			(layers "F.Cu" "F.Mask" "F.Paste")
			(net "TP_U330_XTAL1")
		)
		(pad "8" smd rect
			(at -1.199896 1.999996 270)
			(size 0.1778 0.8128)
			(layers "F.Cu" "F.Mask" "F.Paste")
			(net "GND")
		)
		(pad "9" smd rect
			(at -0.8001 1.999996 270)
			(size 0.1778 0.8128)
			(layers "F.Cu" "F.Mask" "F.Paste")
			(net "FAN_7_TACH_OL_R1")
		)
		(pad "10" smd rect
			(at -0.40005 1.999996 270)
			(size 0.1778 0.8128)
			(layers "F.Cu" "F.Mask" "F.Paste")
			(net "FAN_7_PWM_R1")
		)
		(pad "11" smd rect
			(at 0 1.999996 270)
			(size 0.1778 0.8128)
			(layers "F.Cu" "F.Mask" "F.Paste")
			(net "FAN_6_TACH_OL_R1")
		)
		(pad "12" smd rect
			(at 0.40005 1.999996 270)
			(size 0.1778 0.8128)
			(layers "F.Cu" "F.Mask" "F.Paste")
			(net "FAN_7_TACH_IL_R1")
		)
		(pad "13" smd rect
			(at 0.8001 1.999996 270)
			(size 0.1778 0.8128)
			(layers "F.Cu" "F.Mask" "F.Paste")
			(net "FAN_6_TACH_IL_R1")
		)
		(pad "14" smd rect
			(at 1.199896 1.999996 270)
			(size 0.1778 0.8128)
			(layers "F.Cu" "F.Mask" "F.Paste")
			(net "FAN_6_PWM_R1")
		)
		(pad "15" smd rect
			(at 1.999996 1.199896)
			(size 0.1778 0.8128)
			(layers "F.Cu" "F.Mask" "F.Paste")
			(net "FAN_5_TACH_OL_R1")
		)
		(pad "16" smd rect
			(at 1.999996 0.8001)
			(size 0.1778 0.8128)
			(layers "F.Cu" "F.Mask" "F.Paste")
			(net "FAN_5_PWM_R1")
		)
		(pad "17" smd rect
			(at 1.999996 0.40005)
			(size 0.1778 0.8128)
			(layers "F.Cu" "F.Mask" "F.Paste")
			(net "FAN_4_TACH_OL_R1")
		)
		(pad "18" smd rect
			(at 1.999996 0)
			(size 0.1778 0.8128)
			(layers "F.Cu" "F.Mask" "F.Paste")
			(net "FAN_5_TACH_IL_R1")
		)
		(pad "19" smd rect
			(at 1.999996 -0.40005)
			(size 0.1778 0.8128)
			(layers "F.Cu" "F.Mask" "F.Paste")
			(net "FAN_4_TACH_IL_R1")
		)
		(pad "20" smd rect
			(at 1.999996 -0.8001)
			(size 0.1778 0.8128)
			(layers "F.Cu" "F.Mask" "F.Paste")
			(net "FAN_4_PWM_R1")
		)
		(pad "21" smd rect
			(at 1.999996 -1.199896)
			(size 0.1778 0.8128)
			(layers "F.Cu" "F.Mask" "F.Paste")
			(net "P3V3_AUX")
		)
		(pad "22" smd rect
			(at 1.199896 -1.999996 270)
			(size 0.1778 0.8128)
			(layers "F.Cu" "F.Mask" "F.Paste")
			(net "SMB_PDBV_FAN_R_U330_SDA")
		)
		(pad "23" smd rect
			(at 0.8001 -1.999996 270)
			(size 0.1778 0.8128)
			(layers "F.Cu" "F.Mask" "F.Paste")
			(net "SMB_PDBV_FAN_R_U330_SCL")
		)
		(pad "24" smd rect
			(at 0.40005 -1.999996 270)
			(size 0.1778 0.8128)
			(layers "F.Cu" "F.Mask" "F.Paste")
			(net "U330_FAN FAIL_N")
		)
		(pad "25" smd rect
			(at 0 -1.999996 270)
			(size 0.1778 0.8128)
			(layers "F.Cu" "F.Mask" "F.Paste")
			(net "MAX31790_U330_PWM_START0")
		)
		(pad "26" smd rect
			(at -0.40005 -1.999996 270)
			(size 0.1778 0.8128)
			(layers "F.Cu" "F.Mask" "F.Paste")
			(net "MAX31790_U330_PWM_START1")
		)
		(pad "27" smd rect
			(at -0.8001 -1.999996 270)
			(size 0.1778 0.8128)
			(layers "F.Cu" "F.Mask" "F.Paste")
			(net "U330_FAN FS_N")
		)
		(pad "28" smd rect
			(at -1.199896 -1.999996 270)
			(size 0.1778 0.8128)
			(layers "F.Cu" "F.Mask" "F.Paste")
			(net "NC_U330_CLKOUT")
		)
		(pad "TH" smd rect
			(at 0 0)
			(size 2.7178 2.7178)
			(layers "F.Cu" "F.Mask" "F.Paste")
			(net "GND")
		)
		(zone
			(layer "F.Cu")
			(hatch none 0.5)
			(connect_pads
				(clearance 0)
			)
			(min_thickness 0.25)
			(keepout
				(tracks not_allowed)
				(vias allowed)
				(pads allowed)
				(copperpour not_allowed)
				(footprints allowed)
			)
			(placement
				(enabled no)
				(sheetname "")
			)
			(fill
				(thermal_gap 0.5)
				(thermal_bridge_width 0.5)
				(island_removal_mode 0)
			)
			(polygon
				(pts
					(xy 22.4917 -129.3876) (xy 22.37105 -129.3876) (xy 22.37105 -130.57505) (xy 19.53895 -130.57505)
					(xy 19.53895 -127.74295) (xy 22.37105 -127.74295) (xy 22.37105 -129.3622) (xy 22.4917 -129.3622)
					(xy 22.4917 -127.6223) (xy 19.4183 -127.6223) (xy 19.4183 -130.6957) (xy 22.4917 -130.6957)
				)
			)
		)
	)
	(footprint ""
		(layer "F.Cu")
		(at 18.415 -182.626 180)
		(property "Reference" "R5467"
			(at 0 0 180)
			(layer "F.SilkS")
			(hide yes)
			(effects
				(font
					(size 1.27 1.27)
				)
			)
		)
		(property "Value" ""
			(at 0 0 180)
			(layer "F.Fab")
			(effects
				(font
					(size 1.27 1.27)
				)
			)
		)
		(duplicate_pad_numbers_are_jumpers no)
		(fp_line
			(start 0.7874 0.4064)
			(end -0.7874 0.4064)
			(stroke
				(width 0.1524)
				(type default)
			)
			(layer "F.SilkS")
		)
		(fp_line
			(start 0.7874 -0.4064)
			(end 0.7874 0.4064)
			(stroke
				(width 0.1524)
				(type default)
			)
			(layer "F.SilkS")
		)
		(fp_line
			(start -0.7874 0.4064)
			(end -0.7874 -0.4064)
			(stroke
				(width 0.1524)
				(type default)
			)
			(layer "F.SilkS")
		)
		(fp_line
			(start -0.7874 -0.4064)
			(end 0.7874 -0.4064)
			(stroke
				(width 0.1524)
				(type default)
			)
			(layer "F.SilkS")
		)
		(fp_line
			(start 0.67945 0.3048)
			(end 0.120396 0.3048)
			(stroke
				(width 0.1)
				(type default)
			)
			(layer "F.Fab")
		)
		(fp_line
			(start 0.67945 -0.3048)
			(end 0.67945 0.3048)
			(stroke
				(width 0.1)
				(type default)
			)
			(layer "F.Fab")
		)
		(fp_line
			(start 0.12065 -0.2794)
			(end 0.12065 -0.3048)
			(stroke
				(width 0.1)
				(type default)
			)
			(layer "F.Fab")
		)
		(fp_line
			(start 0.12065 -0.3048)
			(end 0.67945 -0.3048)
			(stroke
				(width 0.1)
				(type default)
			)
			(layer "F.Fab")
		)
		(fp_line
			(start 0.120396 0.3048)
			(end 0.120396 0.2794)
			(stroke
				(width 0.1)
				(type default)
			)
			(layer "F.Fab")
		)
		(fp_line
			(start 0.120396 0.2794)
			(end -0.12065 0.2794)
			(stroke
				(width 0.1)
				(type default)
			)
			(layer "F.Fab")
		)
		(fp_line
			(start -0.12065 0.3048)
			(end -0.67945 0.3048)
			(stroke
				(width 0.1)
				(type default)
			)
			(layer "F.Fab")
		)
		(fp_line
			(start -0.12065 0.2794)
			(end -0.12065 0.3048)
			(stroke
				(width 0.1)
				(type default)
			)
			(layer "F.Fab")
		)
		(fp_line
			(start -0.12065 -0.2794)
			(end 0.12065 -0.2794)
			(stroke
				(width 0.1)
				(type default)
			)
			(layer "F.Fab")
		)
		(fp_line
			(start -0.12065 -0.305054)
			(end -0.12065 -0.2794)
			(stroke
				(width 0.1)
				(type default)
			)
			(layer "F.Fab")
		)
		(fp_line
			(start -0.67945 0.3048)
			(end -0.67945 -0.305054)
			(stroke
				(width 0.1)
				(type default)
			)
			(layer "F.Fab")
		)
		(fp_line
			(start -0.67945 -0.305054)
			(end -0.12065 -0.305054)
			(stroke
				(width 0.1)
				(type default)
			)
			(layer "F.Fab")
		)
		(pad "1" smd circle
			(at -0.40005 0 180)
			(size 0 0)
			(layers "F.Cu" "F.Mask" "F.Paste")
			(net "SMB_PDBV_FAN_SCL")
		)
		(pad "2" smd circle
			(at 0.40005 0 180)
			(size 0 0)
			(layers "F.Cu" "F.Mask" "F.Paste")
			(net "SMB_PDBV_FAN_R_IOX_SCL")
		)
	)
	(footprint ""
		(layer "F.Cu")
		(at 45.085 -187.96 180)
		(property "Reference" "R4965"
			(at 0 0 180)
			(layer "F.SilkS")
			(hide yes)
			(effects
				(font
					(size 1.27 1.27)
				)
			)
		)
		(property "Value" ""
			(at 0 0 180)
			(layer "F.Fab")
			(effects
				(font
					(size 1.27 1.27)
				)
			)
		)
		(duplicate_pad_numbers_are_jumpers no)
		(fp_line
			(start 0.7874 0.4064)
			(end -0.7874 0.4064)
			(stroke
				(width 0.1524)
				(type default)
			)
			(layer "F.SilkS")
		)
		(fp_line
			(start 0.7874 -0.4064)
			(end 0.7874 0.4064)
			(stroke
				(width 0.1524)
				(type default)
			)
			(layer "F.SilkS")
		)
		(fp_line
			(start -0.7874 0.4064)
			(end -0.7874 -0.4064)
			(stroke
				(width 0.1524)
				(type default)
			)
			(layer "F.SilkS")
		)
		(fp_line
			(start -0.7874 -0.4064)
			(end 0.7874 -0.4064)
			(stroke
				(width 0.1524)
				(type default)
			)
			(layer "F.SilkS")
		)
		(fp_line
			(start 0.67945 0.3048)
			(end 0.120396 0.3048)
			(stroke
				(width 0.1)
				(type default)
			)
			(layer "F.Fab")
		)
		(fp_line
			(start 0.67945 -0.3048)
			(end 0.67945 0.3048)
			(stroke
				(width 0.1)
				(type default)
			)
			(layer "F.Fab")
		)
		(fp_line
			(start 0.12065 -0.2794)
			(end 0.12065 -0.3048)
			(stroke
				(width 0.1)
				(type default)
			)
			(layer "F.Fab")
		)
		(fp_line
			(start 0.12065 -0.3048)
			(end 0.67945 -0.3048)
			(stroke
				(width 0.1)
				(type default)
			)
			(layer "F.Fab")
		)
		(fp_line
			(start 0.120396 0.3048)
			(end 0.120396 0.2794)
			(stroke
				(width 0.1)
				(type default)
			)
			(layer "F.Fab")
		)
		(fp_line
			(start 0.120396 0.2794)
			(end -0.12065 0.2794)
			(stroke
				(width 0.1)
				(type default)
			)
			(layer "F.Fab")
		)
		(fp_line
			(start -0.12065 0.3048)
			(end -0.67945 0.3048)
			(stroke
				(width 0.1)
				(type default)
			)
			(layer "F.Fab")
		)
		(fp_line
			(start -0.12065 0.2794)
			(end -0.12065 0.3048)
			(stroke
				(width 0.1)
				(type default)
			)
			(layer "F.Fab")
		)
		(fp_line
			(start -0.12065 -0.2794)
			(end 0.12065 -0.2794)
			(stroke
				(width 0.1)
				(type default)
			)
			(layer "F.Fab")
		)
		(fp_line
			(start -0.12065 -0.305054)
			(end -0.12065 -0.2794)
			(stroke
				(width 0.1)
				(type default)
			)
			(layer "F.Fab")
		)
		(fp_line
			(start -0.67945 0.3048)
			(end -0.67945 -0.305054)
			(stroke
				(width 0.1)
				(type default)
			)
			(layer "F.Fab")
		)
		(fp_line
			(start -0.67945 -0.305054)
			(end -0.12065 -0.305054)
			(stroke
				(width 0.1)
				(type default)
			)
			(layer "F.Fab")
		)
		(pad "1" smd circle
			(at -0.40005 0 180)
			(size 0 0)
			(layers "F.Cu" "F.Mask" "F.Paste")
			(net "GND")
		)
		(pad "2" smd circle
			(at 0.40005 0 180)
			(size 0 0)
			(layers "F.Cu" "F.Mask" "F.Paste")
			(net "PD_FAN_BUFF_INPUT_U337E")
		)
	)
)
